# T6G (Grand Teton) — schematic netlist excerpt (pin names and nets, part order shuffled) for the footprints in the layout excerpt that follows; sources: Cadence DE-HDL packaged netlist, KiCad conversion of 04192023_DAF0TMB3IC0_F0TG_MB_C_brd_V02_OCP.brd

R6754  Q_RES  0 5% CHIP  pkg 0201LF  page 184 : A = SMB_RT_CPU0_P0_SDA ; B = SMB_RT_CPU0_P0_R_SDA
C8007  Q_CAP  0.1UF 25V 10% X7R  pkg 0402  page 153 : A = P1V8_AUX ; B = GND
C671  Q_CAP  10UF 6.3V 20% X6S  pkg C0402  page 301 : A = P1V8_CPU0_RT2_1A ; B = GND

(kicad_pcb
	(version 20260206)
	(generator "pcbnew")
	(generator_version "10.0")
	(general
		(thickness 1.6)
		(legacy_teardrops no)
	)
	(paper "A4")
	(title_block
		(title "04192023_DAF0TMB3IC0_F0TG_MB_C_brd_V02_OCP.brd")
		(comment 1 "Grand Teton / footprints 6732-6734 of 8354")
	)
	(layers
		(0 "F.Cu" signal "TOP")
		(4 "In1.Cu" signal "GND")
		(6 "In2.Cu" signal "IN1")
		(8 "In3.Cu" signal "GND1")
		(10 "In4.Cu" signal "IN2")
		(12 "In5.Cu" signal "GND2")
		(14 "In6.Cu" signal "IN3")
		(16 "In7.Cu" signal "GND3")
		(18 "In8.Cu" signal "VCC")
		(20 "In9.Cu" signal "VCC1")
		(22 "In10.Cu" signal "GND4")
		(24 "In11.Cu" signal "IN4")
		(26 "In12.Cu" signal "GND5")
		(28 "In13.Cu" signal "IN5")
		(30 "In14.Cu" signal "GND6")
		(32 "In15.Cu" signal "IN6")
		(34 "In16.Cu" signal "GND7")
		(2 "B.Cu" signal "BOTTOM")
		(9 "F.Adhes" user "F.Adhesive")
		(11 "B.Adhes" user "B.Adhesive")
		(13 "F.Paste" user "Package Geometry/Pastemask Top")
		(15 "B.Paste" user "Package Geometry/Pastemask Bottom")
		(5 "F.SilkS" user "Ref Des/Silkscreen Top")
		(7 "B.SilkS" user "Ref Des/Silkscreen Bottom")
		(1 "F.Mask" user "Board Geometry/Soldermask Top")
		(3 "B.Mask" user "Board Geometry/Soldermask Bottom")
		(17 "Dwgs.User" user "User.Drawings")
		(19 "Cmts.User" user "User.Comments")
		(21 "Eco1.User" user "User.Eco1")
		(23 "Eco2.User" user "User.Eco2")
		(25 "Edge.Cuts" user "Board Geometry/Outline")
		(27 "Margin" user)
		(31 "F.CrtYd" user "Package Geometry/Place Bound Top")
		(29 "B.CrtYd" user "Package Geometry/Place Bound Bottom")
		(35 "F.Fab" user "Ref Des/Assembly Top")
		(33 "B.Fab" user "Ref Des/Assembly Bottom")
	)
	(footprint ""
		(layer "B.Cu")
		(at 188.138562 -144.58823 180)
		(property "Reference" "C8007"
			(at 0 0 0)
			(layer "B.SilkS")
			(hide yes)
			(effects
				(font
					(size 1.27 1.27)
				)
				(justify mirror)
			)
		)
		(property "Value" ""
			(at 0 0 0)
			(layer "B.Fab")
			(effects
				(font
					(size 1.27 1.27)
				)
				(justify mirror)
			)
		)
		(duplicate_pad_numbers_are_jumpers no)
		(fp_line
			(start 0.7874 0.4064)
			(end 0.7874 -0.4064)
			(stroke
				(width 0.1524)
				(type default)
			)
			(layer "B.SilkS")
		)
		(fp_line
			(start 0.7874 -0.4064)
			(end -0.7874 -0.4064)
			(stroke
				(width 0.1524)
				(type default)
			)
			(layer "B.SilkS")
		)
		(fp_line
			(start -0.7874 0.4064)
			(end 0.7874 0.4064)
			(stroke
				(width 0.1524)
				(type default)
			)
			(layer "B.SilkS")
		)
		(fp_line
			(start -0.7874 -0.4064)
			(end -0.7874 0.4064)
			(stroke
				(width 0.1524)
				(type default)
			)
			(layer "B.SilkS")
		)
		(fp_line
			(start 0.67945 0.3048)
			(end 0.67945 -0.305054)
			(stroke
				(width 0.1)
				(type default)
			)
			(layer "B.Fab")
		)
		(fp_line
			(start 0.67945 -0.305054)
			(end 0.12065 -0.305054)
			(stroke
				(width 0.1)
				(type default)
			)
			(layer "B.Fab")
		)
		(fp_line
			(start 0.12065 0.3048)
			(end 0.67945 0.3048)
			(stroke
				(width 0.1)
				(type default)
			)
			(layer "B.Fab")
		)
		(fp_line
			(start 0.12065 0.2794)
			(end 0.12065 0.3048)
			(stroke
				(width 0.1)
				(type default)
			)
			(layer "B.Fab")
		)
		(fp_line
			(start 0.12065 -0.2794)
			(end -0.12065 -0.2794)
			(stroke
				(width 0.1)
				(type default)
			)
			(layer "B.Fab")
		)
		(fp_line
			(start 0.12065 -0.305054)
			(end 0.12065 -0.2794)
			(stroke
				(width 0.1)
				(type default)
			)
			(layer "B.Fab")
		)
		(fp_line
			(start -0.120396 0.3048)
			(end -0.120396 0.2794)
			(stroke
				(width 0.1)
				(type default)
			)
			(layer "B.Fab")
		)
		(fp_line
			(start -0.120396 0.2794)
			(end 0.12065 0.2794)
			(stroke
				(width 0.1)
				(type default)
			)
			(layer "B.Fab")
		)
		(fp_line
			(start -0.12065 -0.2794)
			(end -0.12065 -0.3048)
			(stroke
				(width 0.1)
				(type default)
			)
			(layer "B.Fab")
		)
		(fp_line
			(start -0.12065 -0.3048)
			(end -0.67945 -0.3048)
			(stroke
				(width 0.1)
				(type default)
			)
			(layer "B.Fab")
		)
		(fp_line
			(start -0.67945 0.3048)
			(end -0.120396 0.3048)
			(stroke
				(width 0.1)
				(type default)
			)
			(layer "B.Fab")
		)
		(fp_line
			(start -0.67945 -0.3048)
			(end -0.67945 0.3048)
			(stroke
				(width 0.1)
				(type default)
			)
			(layer "B.Fab")
		)
		(pad "1" smd circle
			(at 0.40005 0)
			(size 0 0)
			(layers "B.Cu" "B.Mask" "B.Paste")
			(net "P1V8_AUX")
		)
		(pad "2" smd circle
			(at -0.40005 0)
			(size 0 0)
			(layers "B.Cu" "B.Mask" "B.Paste")
			(net "GND")
		)
	)
	(footprint ""
		(layer "B.Cu")
		(at 412.618936 -398.942052 90)
		(property "Reference" "C671"
			(at 0 0 90)
			(layer "B.SilkS")
			(hide yes)
			(effects
				(font
					(size 1.27 1.27)
				)
				(justify mirror)
			)
		)
		(property "Value" ""
			(at 0 0 90)
			(layer "B.Fab")
			(effects
				(font
					(size 1.27 1.27)
				)
				(justify mirror)
			)
		)
		(duplicate_pad_numbers_are_jumpers no)
		(fp_line
			(start 0.7874 -0.4064)
			(end -0.7874 -0.4064)
			(stroke
				(width 0.1524)
				(type default)
			)
			(layer "B.SilkS")
		)
		(fp_line
			(start -0.7874 -0.4064)
			(end -0.7874 0.4064)
			(stroke
				(width 0.1524)
				(type default)
			)
			(layer "B.SilkS")
		)
		(fp_line
			(start 0.7874 0.4064)
			(end 0.7874 -0.4064)
			(stroke
				(width 0.1524)
				(type default)
			)
			(layer "B.SilkS")
		)
		(fp_line
			(start -0.7874 0.4064)
			(end 0.7874 0.4064)
			(stroke
				(width 0.1524)
				(type default)
			)
			(layer "B.SilkS")
		)
		(fp_line
			(start 0.67945 -0.305054)
			(end 0.12065 -0.305054)
			(stroke
				(width 0.1)
				(type default)
			)
			(layer "B.Fab")
		)
		(fp_line
			(start 0.12065 -0.305054)
			(end 0.12065 -0.2794)
			(stroke
				(width 0.1)
				(type default)
			)
			(layer "B.Fab")
		)
		(fp_line
			(start -0.12065 -0.3048)
			(end -0.67945 -0.3048)
			(stroke
				(width 0.1)
				(type default)
			)
			(layer "B.Fab")
		)
		(fp_line
			(start -0.67945 -0.3048)
			(end -0.67945 0.3048)
			(stroke
				(width 0.1)
				(type default)
			)
			(layer "B.Fab")
		)
		(fp_line
			(start 0.12065 -0.2794)
			(end -0.12065 -0.2794)
			(stroke
				(width 0.1)
				(type default)
			)
			(layer "B.Fab")
		)
		(fp_line
			(start -0.12065 -0.2794)
			(end -0.12065 -0.3048)
			(stroke
				(width 0.1)
				(type default)
			)
			(layer "B.Fab")
		)
		(fp_line
			(start 0.12065 0.2794)
			(end 0.12065 0.3048)
			(stroke
				(width 0.1)
				(type default)
			)
			(layer "B.Fab")
		)
		(fp_line
			(start -0.120396 0.2794)
			(end 0.12065 0.2794)
			(stroke
				(width 0.1)
				(type default)
			)
			(layer "B.Fab")
		)
		(fp_line
			(start 0.67945 0.3048)
			(end 0.67945 -0.305054)
			(stroke
				(width 0.1)
				(type default)
			)
			(layer "B.Fab")
		)
		(fp_line
			(start 0.12065 0.3048)
			(end 0.67945 0.3048)
			(stroke
				(width 0.1)
				(type default)
			)
			(layer "B.Fab")
		)
		(fp_line
			(start -0.120396 0.3048)
			(end -0.120396 0.2794)
			(stroke
				(width 0.1)
				(type default)
			)
			(layer "B.Fab")
		)
		(fp_line
			(start -0.67945 0.3048)
			(end -0.120396 0.3048)
			(stroke
				(width 0.1)
				(type default)
			)
			(layer "B.Fab")
		)
		(pad "1" smd circle
			(at 0.40005 0 270)
			(size 0 0)
			(layers "B.Cu" "B.Mask" "B.Paste")
			(net "P1V8_CPU0_RT2_1A")
		)
		(pad "2" smd circle
			(at -0.40005 0 270)
			(size 0 0)
			(layers "B.Cu" "B.Mask" "B.Paste")
			(net "GND")
		)
	)
	(footprint ""
		(layer "B.Cu")
		(at 229.8446 -341.884 180)
		(property "Reference" "R6754"
			(at 0 0 0)
			(layer "B.SilkS")
			(hide yes)
			(effects
				(font
					(size 1.27 1.27)
				)
				(justify mirror)
			)
		)
		(property "Value" ""
			(at 0 0 0)
			(layer "B.Fab")
			(effects
				(font
					(size 1.27 1.27)
				)
				(justify mirror)
			)
		)
		(duplicate_pad_numbers_are_jumpers no)
		(fp_line
			(start 0.32512 0.175006)
			(end 0.32512 -0.175006)
			(stroke
				(width 0.1)
				(type default)
			)
			(layer "B.Fab")
		)
		(fp_line
			(start 0.32512 -0.175006)
			(end -0.32512 -0.175006)
			(stroke
				(width 0.1)
				(type default)
			)
			(layer "B.Fab")
		)
		(fp_line
			(start -0.32512 0.175006)
			(end 0.32512 0.175006)
			(stroke
				(width 0.1)
				(type default)
			)
			(layer "B.Fab")
		)
		(fp_line
			(start -0.32512 -0.175006)
			(end -0.32512 0.175006)
			(stroke
				(width 0.1)
				(type default)
			)
			(layer "B.Fab")
		)
		(pad "1" smd rect
			(at 0.2667 0)
			(size 0.3048 0.381)
			(layers "B.Cu" "B.Mask" "B.Paste")
			(net "SMB_RT_CPU0_P0_SDA")
		)
		(pad "2" smd rect
			(at -0.2667 0 180)
			(size 0.3048 0.381)
			(layers "B.Cu" "B.Mask" "B.Paste")
			(net "SMB_RT_CPU0_P0_R_SDA")
		)
	)
)
